M48
INCH,TZ
T01C.01
T02C.012
T03C.028
T04C.071
T05C.086
T06C.093
T07C.139
;EXTENTS: -102.215 -107.091 114.785 105.109 
;LEADER: 12 
;HEADER: 
;CODE  : ASCII 
;FILE  : 15968-1a.rou for board 15968-1a.brd
%
G90
F1
M16
G40
M30
